(kicad_pcb
	(version 20260206)
	(generator "pcbnew")
	(generator_version "10.0")
	(general
		(thickness 1.6)
		(legacy_teardrops no)
	)
	(paper "A4")
	(title_block
		(title "Wiwynn_Tioga_Pass_MB.brd")
		(comment 1 "Tioga Pass / footprints 2064-2070 of 4770")
	)
	(layers
		(0 "F.Cu" signal "TOP")
		(4 "In1.Cu" signal "L2GND")
		(6 "In2.Cu" signal "L3")
		(8 "In3.Cu" signal "L4GND")
		(10 "In4.Cu" signal "L5")
		(12 "In5.Cu" signal "L6GND")
		(14 "In6.Cu" signal "L7VCC")
		(16 "In7.Cu" signal "L8VCC")
		(18 "In8.Cu" signal "L9GND")
		(20 "In9.Cu" signal "L10")
		(22 "In10.Cu" signal "L11GND")
		(24 "In11.Cu" signal "L12")
		(26 "In12.Cu" signal "L13GND")
		(2 "B.Cu" signal "BOTTOM")
		(9 "F.Adhes" user "F.Adhesive")
		(11 "B.Adhes" user "B.Adhesive")
		(13 "F.Paste" user "Package Geometry/Pastemask Top")
		(15 "B.Paste" user "Package Geometry/Pastemask Bottom")
		(5 "F.SilkS" user "Ref Des/Silkscreen Top")
		(7 "B.SilkS" user "Ref Des/Silkscreen Bottom")
		(1 "F.Mask" user "Board Geometry/Soldermask Top")
		(3 "B.Mask" user "Board Geometry/Soldermask Bottom")
		(17 "Dwgs.User" user "User.Drawings")
		(19 "Cmts.User" user "User.Comments")
		(21 "Eco1.User" user "User.Eco1")
		(23 "Eco2.User" user "User.Eco2")
		(25 "Edge.Cuts" user "Board Geometry/Outline")
		(27 "Margin" user)
		(31 "F.CrtYd" user "Package Geometry/Place Bound Top")
		(29 "B.CrtYd" user "Package Geometry/Place Bound Bottom")
		(35 "F.Fab" user "Ref Des/Assembly Top")
		(33 "B.Fab" user "Ref Des/Assembly Bottom")
	)
	(footprint ""
		(layer "F.Cu")
		(at 312.650124 -30.26537)
		(property "Reference" "Y6F1"
			(at -0.1397 -2.153412 0)
			(unlocked yes)
			(layer "F.SilkS")
			(effects
				(font
					(size 0.7874 0.5842)
					(thickness 0.1524)
				)
				(justify left)
			)
		)
		(property "Value" ""
			(at 0 0 0)
			(layer "F.Fab")
			(effects
				(font
					(size 1.27 1.27)
				)
			)
		)
		(duplicate_pad_numbers_are_jumpers no)
		(fp_line
			(start -0.366522 -1.329944)
			(end 3.033522 -1.329944)
			(stroke
				(width 0.1524)
				(type default)
			)
			(layer "F.SilkS")
		)
		(fp_line
			(start -0.366522 -0.80391)
			(end -0.366522 -1.329944)
			(stroke
				(width 0.1524)
				(type default)
			)
			(layer "F.SilkS")
		)
		(fp_line
			(start -0.366522 3.869944)
			(end -0.366522 3.363468)
			(stroke
				(width 0.1524)
				(type default)
			)
			(layer "F.SilkS")
		)
		(fp_line
			(start 3.033522 -1.329944)
			(end 3.033522 -0.790956)
			(stroke
				(width 0.1524)
				(type default)
			)
			(layer "F.SilkS")
		)
		(fp_line
			(start 3.033522 3.370072)
			(end 3.033522 3.869944)
			(stroke
				(width 0.1524)
				(type default)
			)
			(layer "F.SilkS")
		)
		(fp_line
			(start 3.033522 3.869944)
			(end -0.366522 3.869944)
			(stroke
				(width 0.1524)
				(type default)
			)
			(layer "F.SilkS")
		)
		(fp_circle
			(center -1.406398 -0.537718)
			(end -1.279398 -0.537718)
			(stroke
				(width 0.254)
				(type default)
			)
			(fill no)
			(layer "F.SilkS")
		)
		(fp_rect
			(start -0.366522 3.869944)
			(end 3.033522 -1.329944)
			(stroke
				(width 0)
				(type default)
			)
			(fill no)
			(layer "F.CrtYd")
		)
		(fp_line
			(start -0.366522 -1.329944)
			(end 3.033522 -1.329944)
			(stroke
				(width 0.1)
				(type default)
			)
			(layer "F.Fab")
		)
		(fp_line
			(start -0.366522 3.869944)
			(end -0.366522 -1.329944)
			(stroke
				(width 0.1)
				(type default)
			)
			(layer "F.Fab")
		)
		(fp_line
			(start 3.033522 -1.329944)
			(end 3.033522 3.869944)
			(stroke
				(width 0.1)
				(type default)
			)
			(layer "F.Fab")
		)
		(fp_line
			(start 3.033522 3.869944)
			(end -0.366522 3.869944)
			(stroke
				(width 0.1)
				(type default)
			)
			(layer "F.Fab")
		)
		(fp_circle
			(center -1.405128 -0.544068)
			(end -1.278128 -0.544068)
			(stroke
				(width 0.254)
				(type default)
			)
			(fill no)
			(layer "F.Fab")
		)
		(pad "1" smd rect
			(at 0 0)
			(size 1.651 0.8382)
			(layers "F.Cu" "F.Mask" "F.Paste")
			(net "FM_CPU0_STL_BRD_OSC_EN")
		)
		(pad "2" smd rect
			(at 0 1.27)
			(size 1.651 0.8382)
			(layers "F.Cu" "F.Mask" "F.Paste")
			(net "NC_CLK_156M_CPU0_OSC")
		)
		(pad "3" smd rect
			(at 0 2.54)
			(size 1.651 0.8382)
			(layers "F.Cu" "F.Mask" "F.Paste")
			(net "GND")
		)
		(pad "4" smd rect
			(at 2.667 2.54)
			(size 1.651 0.8382)
			(layers "F.Cu" "F.Mask" "F.Paste")
			(net "CLK_156M_OSC_BRD_CPU0_DP")
		)
		(pad "5" smd rect
			(at 2.667 1.27)
			(size 1.651 0.8382)
			(layers "F.Cu" "F.Mask" "F.Paste")
			(net "CLK_156M_OSC_BRD_CPU0_DN")
		)
		(pad "6" smd rect
			(at 2.667 0)
			(size 1.651 0.8382)
			(layers "F.Cu" "F.Mask" "F.Paste")
			(net "P3V3")
		)
	)
	(footprint ""
		(layer "F.Cu")
		(at 211.831936 11.952478 -90)
		(property "Reference" "T1P3"
			(at 0 0 270)
			(layer "F.SilkS")
			(hide yes)
			(effects
				(font
					(size 1.27 1.27)
				)
			)
		)
		(property "Value" "*"
			(at -3.302 1.12395 270)
			(unlocked yes)
			(layer "F.Fab")
			(hide yes)
			(effects
				(font
					(size 0.889 0.889)
					(thickness 0.1524)
				)
			)
		)
		(property "Device Type" "TPAD-DIFF-4P-GP_DISCRET-GB3-TPA"
			(at -3.302 -0.40005 270)
			(unlocked yes)
			(layer "F.Fab")
			(hide yes)
			(effects
				(font
					(size 0.889 0.889)
					(thickness 0.1524)
				)
			)
		)
		(duplicate_pad_numbers_are_jumpers no)
		(fp_line
			(start -2.286 2.286)
			(end 2.286 2.286)
			(stroke
				(width 0.1524)
				(type default)
			)
			(layer "F.SilkS")
		)
		(fp_line
			(start 2.286 2.286)
			(end 2.286 -2.286)
			(stroke
				(width 0.1524)
				(type default)
			)
			(layer "F.SilkS")
		)
		(fp_line
			(start -2.286 -2.286)
			(end -2.286 2.286)
			(stroke
				(width 0.1524)
				(type default)
			)
			(layer "F.SilkS")
		)
		(fp_line
			(start 2.286 -2.286)
			(end -2.286 -2.286)
			(stroke
				(width 0.1524)
				(type default)
			)
			(layer "F.SilkS")
		)
		(fp_line
			(start -2.413 -2.413)
			(end -2.413 -1.143)
			(stroke
				(width 0.4064)
				(type default)
			)
			(layer "F.SilkS")
		)
		(fp_line
			(start -1.143 -2.413)
			(end -2.413 -2.413)
			(stroke
				(width 0.4064)
				(type default)
			)
			(layer "F.SilkS")
		)
		(fp_rect
			(start -2.54 2.54)
			(end 2.54 -2.54)
			(stroke
				(width 0)
				(type default)
			)
			(fill no)
			(layer "F.CrtYd")
		)
		(fp_rect
			(start -2.54 2.54)
			(end 2.54 -2.54)
			(stroke
				(width 0)
				(type default)
			)
			(fill no)
			(layer "F.Fab")
		)
		(pad "1" thru_hole circle
			(at -1.27 -1.27 270)
			(size 1.524 1.524)
			(drill 0.9144)
			(layers "*.Cu" "*.Mask")
			(remove_unused_layers no)
			(net "L5_85OHM_6INCH_DP")
			(clearance -0.0508)
			(thermal_gap 0.127)
			(padstack
				(mode front_inner_back)
				(layer "Inner"
					(shape circle)
					(size 1.1684 1.1684)
					(clearance 0.127)
				)
				(layer "B.Cu"
					(shape circle)
					(size 1.524 1.524)
					(clearance -0.0508)
				)
			)
		)
		(pad "2" thru_hole circle
			(at 1.27 -1.27 270)
			(size 1.524 1.524)
			(drill 0.9144)
			(layers "*.Cu" "*.Mask")
			(remove_unused_layers no)
			(net "L5_85OHM_6INCH_DN")
			(clearance -0.0508)
			(thermal_gap 0.127)
			(padstack
				(mode front_inner_back)
				(layer "Inner"
					(shape circle)
					(size 1.1684 1.1684)
					(clearance 0.127)
				)
				(layer "B.Cu"
					(shape circle)
					(size 1.524 1.524)
					(clearance -0.0508)
				)
			)
		)
		(pad "GND1" thru_hole rect
			(at -1.27 1.27 270)
			(size 1.524 1.524)
			(drill 0.9144)
			(layers "*.Cu" "*.Mask")
			(remove_unused_layers no)
			(net "GND")
			(clearance -0.0508)
			(thermal_gap 0.127)
			(padstack
				(mode front_inner_back)
				(layer "Inner"
					(shape circle)
					(size 1.1684 1.1684)
					(clearance 0.127)
				)
				(layer "B.Cu"
					(shape rect)
					(size 1.524 1.524)
					(clearance -0.0508)
				)
			)
		)
		(pad "GND2" thru_hole rect
			(at 1.27 1.27 270)
			(size 1.524 1.524)
			(drill 0.9144)
			(layers "*.Cu" "*.Mask")
			(remove_unused_layers no)
			(net "GND")
			(clearance -0.0508)
			(thermal_gap 0.127)
			(padstack
				(mode front_inner_back)
				(layer "Inner"
					(shape circle)
					(size 1.1684 1.1684)
					(clearance 0.127)
				)
				(layer "B.Cu"
					(shape rect)
					(size 1.524 1.524)
					(clearance -0.0508)
				)
			)
		)
	)
	(footprint ""
		(layer "F.Cu")
		(at 108.839 -68.072 90)
		(property "Reference" "R3D27"
			(at 0 0 90)
			(layer "F.SilkS")
			(hide yes)
			(effects
				(font
					(size 1.27 1.27)
				)
			)
		)
		(property "Value" ""
			(at 0 0 90)
			(layer "F.Fab")
			(effects
				(font
					(size 1.27 1.27)
				)
			)
		)
		(duplicate_pad_numbers_are_jumpers no)
		(fp_poly
			(pts
				(xy -0.2794 -0.1016) (xy 0.2794 -0.1016) (xy 0.2794 0.9906) (xy -0.2794 0.9906)
			)
			(stroke
				(width 0)
				(type default)
			)
			(fill no)
			(layer "F.CrtYd")
		)
		(fp_line
			(start 0.2794 -0.1016)
			(end -0.2794 -0.1016)
			(stroke
				(width 0.1)
				(type default)
			)
			(layer "F.Fab")
		)
		(fp_line
			(start -0.2794 -0.1016)
			(end -0.2794 0.9906)
			(stroke
				(width 0.1)
				(type default)
			)
			(layer "F.Fab")
		)
		(fp_line
			(start 0.2794 0.9906)
			(end 0.2794 -0.1016)
			(stroke
				(width 0.1)
				(type default)
			)
			(layer "F.Fab")
		)
		(fp_line
			(start -0.2794 0.9906)
			(end 0.2794 0.9906)
			(stroke
				(width 0.1)
				(type default)
			)
			(layer "F.Fab")
		)
		(pad "1" smd rect
			(at 0 0 90)
			(size 0.508 0.508)
			(layers "F.Cu" "F.Mask" "F.Paste")
			(net "VSENSE_PMAX_CPU1")
		)
		(pad "2" smd rect
			(at 0 0.889 90)
			(size 0.508 0.508)
			(layers "F.Cu" "F.Mask" "F.Paste")
			(net "GND")
		)
		(zone
			(layer "F.Cu")
			(hatch none 0.5)
			(connect_pads
				(clearance 0)
			)
			(min_thickness 0.25)
			(keepout
				(tracks allowed)
				(vias not_allowed)
				(pads allowed)
				(copperpour not_allowed)
				(footprints allowed)
			)
			(placement
				(enabled no)
				(sheetname "")
			)
			(fill
				(thermal_gap 0.5)
				(thermal_bridge_width 0.5)
				(island_removal_mode 0)
			)
			(polygon
				(pts
					(xy 109.093 -67.818) (xy 109.093 -68.326) (xy 109.474 -68.326) (xy 109.474 -67.818)
				)
			)
		)
		(zone
			(layer "F.Cu")
			(hatch none 0.5)
			(connect_pads
				(clearance 0)
			)
			(min_thickness 0.25)
			(keepout
				(tracks not_allowed)
				(vias allowed)
				(pads allowed)
				(copperpour not_allowed)
				(footprints allowed)
			)
			(placement
				(enabled no)
				(sheetname "")
			)
			(fill
				(thermal_gap 0.5)
				(thermal_bridge_width 0.5)
				(island_removal_mode 0)
			)
			(polygon
				(pts
					(xy 109.474 -67.818) (xy 109.474 -68.326) (xy 109.093 -68.326) (xy 109.093 -67.818)
				)
			)
		)
	)
	(footprint ""
		(layer "F.Cu")
		(at 348.0054 -19.304 180)
		(property "Reference" "C7F16"
			(at 0 0 180)
			(layer "F.SilkS")
			(hide yes)
			(effects
				(font
					(size 1.27 1.27)
				)
			)
		)
		(property "Value" ""
			(at 0 0 180)
			(layer "F.Fab")
			(effects
				(font
					(size 1.27 1.27)
				)
			)
		)
		(duplicate_pad_numbers_are_jumpers no)
		(fp_poly
			(pts
				(xy 0.3048 -0.1016) (xy 0.3048 0.9906) (xy -0.3048 0.9906) (xy -0.3048 -0.1016)
			)
			(stroke
				(width 0)
				(type default)
			)
			(fill no)
			(layer "F.CrtYd")
		)
		(fp_line
			(start 0.3048 0.9906)
			(end 0.3048 -0.1016)
			(stroke
				(width 0.1)
				(type default)
			)
			(layer "F.Fab")
		)
		(fp_line
			(start 0.3048 -0.1016)
			(end -0.3048 -0.1016)
			(stroke
				(width 0.1)
				(type default)
			)
			(layer "F.Fab")
		)
		(fp_line
			(start -0.3048 0.9906)
			(end 0.3048 0.9906)
			(stroke
				(width 0.1)
				(type default)
			)
			(layer "F.Fab")
		)
		(fp_line
			(start -0.3048 -0.1016)
			(end -0.3048 0.9906)
			(stroke
				(width 0.1)
				(type default)
			)
			(layer "F.Fab")
		)
		(pad "1" smd rect
			(at 0 0 180)
			(size 0.508 0.508)
			(layers "F.Cu" "F.Mask" "F.Paste")
			(net "VR_PVDDQ_ABC_VD12")
		)
		(pad "2" smd rect
			(at 0 0.889 180)
			(size 0.508 0.508)
			(layers "F.Cu" "F.Mask" "F.Paste")
			(net "GND")
		)
		(zone
			(layer "F.Cu")
			(hatch none 0.5)
			(connect_pads
				(clearance 0)
			)
			(min_thickness 0.25)
			(keepout
				(tracks not_allowed)
				(vias allowed)
				(pads allowed)
				(copperpour not_allowed)
				(footprints allowed)
			)
			(placement
				(enabled no)
				(sheetname "")
			)
			(fill
				(thermal_gap 0.5)
				(thermal_bridge_width 0.5)
				(island_removal_mode 0)
			)
			(polygon
				(pts
					(xy 348.2594 -19.939) (xy 347.7514 -19.939) (xy 347.7514 -19.558) (xy 348.2594 -19.558)
				)
			)
		)
		(zone
			(layer "F.Cu")
			(hatch none 0.5)
			(connect_pads
				(clearance 0)
			)
			(min_thickness 0.25)
			(keepout
				(tracks allowed)
				(vias not_allowed)
				(pads allowed)
				(copperpour not_allowed)
				(footprints allowed)
			)
			(placement
				(enabled no)
				(sheetname "")
			)
			(fill
				(thermal_gap 0.5)
				(thermal_bridge_width 0.5)
				(island_removal_mode 0)
			)
			(polygon
				(pts
					(xy 348.2594 -19.558) (xy 347.7514 -19.558) (xy 347.7514 -19.939) (xy 348.2594 -19.939)
				)
			)
		)
	)
	(footprint ""
		(layer "F.Cu")
		(at 466.344 -41.0972)
		(property "Reference" "C9E11"
			(at 0 0 0)
			(layer "F.SilkS")
			(hide yes)
			(effects
				(font
					(size 1.27 1.27)
				)
			)
		)
		(property "Value" ""
			(at 0 0 0)
			(layer "F.Fab")
			(effects
				(font
					(size 1.27 1.27)
				)
			)
		)
		(duplicate_pad_numbers_are_jumpers no)
		(fp_poly
			(pts
				(xy 0.3048 -0.1016) (xy 0.3048 0.9906) (xy -0.3048 0.9906) (xy -0.3048 -0.1016)
			)
			(stroke
				(width 0)
				(type default)
			)
			(fill no)
			(layer "F.CrtYd")
		)
		(fp_line
			(start -0.3048 -0.1016)
			(end -0.3048 0.9906)
			(stroke
				(width 0.1)
				(type default)
			)
			(layer "F.Fab")
		)
		(fp_line
			(start -0.3048 0.9906)
			(end 0.3048 0.9906)
			(stroke
				(width 0.1)
				(type default)
			)
			(layer "F.Fab")
		)
		(fp_line
			(start 0.3048 -0.1016)
			(end -0.3048 -0.1016)
			(stroke
				(width 0.1)
				(type default)
			)
			(layer "F.Fab")
		)
		(fp_line
			(start 0.3048 0.9906)
			(end 0.3048 -0.1016)
			(stroke
				(width 0.1)
				(type default)
			)
			(layer "F.Fab")
		)
		(pad "1" smd rect
			(at 0 0)
			(size 0.508 0.508)
			(layers "F.Cu" "F.Mask" "F.Paste")
			(net "P3V3_STBY")
		)
		(pad "2" smd rect
			(at 0 0.889)
			(size 0.508 0.508)
			(layers "F.Cu" "F.Mask" "F.Paste")
			(net "GND")
		)
		(zone
			(layer "F.Cu")
			(hatch none 0.5)
			(connect_pads
				(clearance 0)
			)
			(min_thickness 0.25)
			(keepout
				(tracks allowed)
				(vias not_allowed)
				(pads allowed)
				(copperpour not_allowed)
				(footprints allowed)
			)
			(placement
				(enabled no)
				(sheetname "")
			)
			(fill
				(thermal_gap 0.5)
				(thermal_bridge_width 0.5)
				(island_removal_mode 0)
			)
			(polygon
				(pts
					(xy 466.09 -40.8432) (xy 466.598 -40.8432) (xy 466.598 -40.4622) (xy 466.09 -40.4622)
				)
			)
		)
		(zone
			(layer "F.Cu")
			(hatch none 0.5)
			(connect_pads
				(clearance 0)
			)
			(min_thickness 0.25)
			(keepout
				(tracks not_allowed)
				(vias allowed)
				(pads allowed)
				(copperpour not_allowed)
				(footprints allowed)
			)
			(placement
				(enabled no)
				(sheetname "")
			)
			(fill
				(thermal_gap 0.5)
				(thermal_bridge_width 0.5)
				(island_removal_mode 0)
			)
			(polygon
				(pts
					(xy 466.09 -40.4622) (xy 466.598 -40.4622) (xy 466.598 -40.8432) (xy 466.09 -40.8432)
				)
			)
		)
	)
	(footprint ""
		(layer "F.Cu")
		(at 13.8938 -29.464 90)
		(property "Reference" "C1F12"
			(at 0 0 90)
			(layer "F.SilkS")
			(hide yes)
			(effects
				(font
					(size 1.27 1.27)
				)
			)
		)
		(property "Value" ""
			(at 0 0 90)
			(layer "F.Fab")
			(effects
				(font
					(size 1.27 1.27)
				)
			)
		)
		(duplicate_pad_numbers_are_jumpers no)
		(fp_rect
			(start -0.3048 -0.1016)
			(end 0.3048 0.9906)
			(stroke
				(width 0)
				(type default)
			)
			(fill no)
			(layer "F.CrtYd")
		)
		(fp_line
			(start 0.3048 -0.1016)
			(end -0.3048 -0.1016)
			(stroke
				(width 0.1)
				(type default)
			)
			(layer "F.Fab")
		)
		(fp_line
			(start -0.3048 -0.1016)
			(end -0.3048 0.9906)
			(stroke
				(width 0.1)
				(type default)
			)
			(layer "F.Fab")
		)
		(fp_line
			(start 0.3048 0.9906)
			(end 0.3048 -0.1016)
			(stroke
				(width 0.1)
				(type default)
			)
			(layer "F.Fab")
		)
		(fp_line
			(start -0.3048 0.9906)
			(end 0.3048 0.9906)
			(stroke
				(width 0.1)
				(type default)
			)
			(layer "F.Fab")
		)
		(pad "1" smd rect
			(at 0 0 90)
			(size 0.508 0.508)
			(layers "F.Cu" "F.Mask" "F.Paste")
			(net "P3E_CPU1_PE3_MP_C_TXP<3>")
		)
		(pad "2" smd rect
			(at 0 0.889 90)
			(size 0.508 0.508)
			(layers "F.Cu" "F.Mask" "F.Paste")
			(net "P3E_CPU1_PE3_MP_TXP<3>")
		)
		(zone
			(layer "F.Cu")
			(hatch none 0.5)
			(connect_pads
				(clearance 0)
			)
			(min_thickness 0.25)
			(keepout
				(tracks allowed)
				(vias not_allowed)
				(pads allowed)
				(copperpour not_allowed)
				(footprints allowed)
			)
			(placement
				(enabled no)
				(sheetname "")
			)
			(fill
				(thermal_gap 0.5)
				(thermal_bridge_width 0.5)
				(island_removal_mode 0)
			)
			(polygon
				(pts
					(xy 14.1478 -29.21) (xy 14.5288 -29.21) (xy 14.5288 -29.718) (xy 14.1478 -29.718)
				)
			)
		)
		(zone
			(layer "F.Cu")
			(hatch none 0.5)
			(connect_pads
				(clearance 0)
			)
			(min_thickness 0.25)
			(keepout
				(tracks not_allowed)
				(vias allowed)
				(pads allowed)
				(copperpour not_allowed)
				(footprints allowed)
			)
			(placement
				(enabled no)
				(sheetname "")
			)
			(fill
				(thermal_gap 0.5)
				(thermal_bridge_width 0.5)
				(island_removal_mode 0)
			)
			(polygon
				(pts
					(xy 14.1478 -29.21) (xy 14.5288 -29.21) (xy 14.5288 -29.718) (xy 14.1478 -29.718)
				)
			)
		)
	)
	(footprint ""
		(layer "F.Cu")
		(at 382.27 -87.3125 180)
		(property "Reference" "R7D7"
			(at 0 0 180)
			(layer "F.SilkS")
			(hide yes)
			(effects
				(font
					(size 1.27 1.27)
				)
			)
		)
		(property "Value" ""
			(at 0 0 180)
			(layer "F.Fab")
			(effects
				(font
					(size 1.27 1.27)
				)
			)
		)
		(duplicate_pad_numbers_are_jumpers no)
		(fp_poly
			(pts
				(xy -0.2794 -0.1016) (xy 0.2794 -0.1016) (xy 0.2794 0.9906) (xy -0.2794 0.9906)
			)
			(stroke
				(width 0)
				(type default)
			)
			(fill no)
			(layer "F.CrtYd")
		)
		(fp_line
			(start 0.2794 0.9906)
			(end 0.2794 -0.1016)
			(stroke
				(width 0.1)
				(type default)
			)
			(layer "F.Fab")
		)
		(fp_line
			(start 0.2794 -0.1016)
			(end -0.2794 -0.1016)
			(stroke
				(width 0.1)
				(type default)
			)
			(layer "F.Fab")
		)
		(fp_line
			(start -0.2794 0.9906)
			(end 0.2794 0.9906)
			(stroke
				(width 0.1)
				(type default)
			)
			(layer "F.Fab")
		)
		(fp_line
			(start -0.2794 -0.1016)
			(end -0.2794 0.9906)
			(stroke
				(width 0.1)
				(type default)
			)
			(layer "F.Fab")
		)
		(pad "1" smd rect
			(at 0 0 180)
			(size 0.508 0.508)
			(layers "F.Cu" "F.Mask" "F.Paste")
			(net "P3V3_STBY")
		)
		(pad "2" smd rect
			(at 0 0.889 180)
			(size 0.508 0.508)
			(layers "F.Cu" "F.Mask" "F.Paste")
			(net "IRQ_PIRQA_SPI_TPM_N")
		)
		(zone
			(layer "F.Cu")
			(hatch none 0.5)
			(connect_pads
				(clearance 0)
			)
			(min_thickness 0.25)
			(keepout
				(tracks not_allowed)
				(vias allowed)
				(pads allowed)
				(copperpour not_allowed)
				(footprints allowed)
			)
			(placement
				(enabled no)
				(sheetname "")
			)
			(fill
				(thermal_gap 0.5)
				(thermal_bridge_width 0.5)
				(island_removal_mode 0)
			)
			(polygon
				(pts
					(xy 382.524 -87.9475) (xy 382.016 -87.9475) (xy 382.016 -87.5665) (xy 382.524 -87.5665)
				)
			)
		)
		(zone
			(layer "F.Cu")
			(hatch none 0.5)
			(connect_pads
				(clearance 0)
			)
			(min_thickness 0.25)
			(keepout
				(tracks allowed)
				(vias not_allowed)
				(pads allowed)
				(copperpour not_allowed)
				(footprints allowed)
			)
			(placement
				(enabled no)
				(sheetname "")
			)
			(fill
				(thermal_gap 0.5)
				(thermal_bridge_width 0.5)
				(island_removal_mode 0)
			)
			(polygon
				(pts
					(xy 382.524 -87.5665) (xy 382.016 -87.5665) (xy 382.016 -87.9475) (xy 382.524 -87.9475)
				)
			)
		)
	)
)
